# SCM (Grand Teton) — schematic netlist excerpt (pin names and nets, part order shuffled) for the footprints in the layout excerpt that follows; sources: Cadence DE-HDL packaged netlist, KiCad conversion of 12092022_DA0F0TMDCD0_F0T_Management_Board_D_brd_V3_OCP.brd

U31  74LVC1G07GW  IC  pkg SOT353_Q  page 50
  NC  = TP_PWR_BUF
  A  = REAR_PWR_BTN_N
  GND  = GND
  Y  = PWR_BTN_BMC_N
  VCC  = P3V3_AUX

R201  Q_RES  33.2 1% CHIP  pkg 0402LF  page 14 : A = I3C4_SDA_R ; B = I3C4_SPD_SDA

(kicad_pcb
	(version 20260206)
	(generator "pcbnew")
	(generator_version "10.0")
	(general
		(thickness 1.6)
		(legacy_teardrops no)
	)
	(paper "A4")
	(title_block
		(title "12092022_DA0F0TMDCD0_F0T_Management_Board_D_brd_V3_OCP.brd")
		(comment 1 "Grand Teton / footprints 493-494 of 1440")
	)
	(layers
		(0 "F.Cu" signal "TOP")
		(4 "In1.Cu" signal "GND")
		(6 "In2.Cu" signal "IN1")
		(8 "In3.Cu" signal "GND1")
		(10 "In4.Cu" signal "IN2")
		(12 "In5.Cu" signal "VCC")
		(14 "In6.Cu" signal "VCC1")
		(16 "In7.Cu" signal "IN3")
		(18 "In8.Cu" signal "GND2")
		(20 "In9.Cu" signal "IN4")
		(22 "In10.Cu" signal "GND3")
		(2 "B.Cu" signal "BOTTOM")
		(9 "F.Adhes" user "F.Adhesive")
		(11 "B.Adhes" user "B.Adhesive")
		(13 "F.Paste" user "Package Geometry/Pastemask Top")
		(15 "B.Paste" user "Package Geometry/Pastemask Bottom")
		(5 "F.SilkS" user "Ref Des/Silkscreen Top")
		(7 "B.SilkS" user "Ref Des/Silkscreen Bottom")
		(1 "F.Mask" user "Board Geometry/Soldermask Top")
		(3 "B.Mask" user "Board Geometry/Soldermask Bottom")
		(17 "Dwgs.User" user "User.Drawings")
		(19 "Cmts.User" user "User.Comments")
		(21 "Eco1.User" user "User.Eco1")
		(23 "Eco2.User" user "User.Eco2")
		(25 "Edge.Cuts" user "Board Geometry/Outline")
		(27 "Margin" user)
		(31 "F.CrtYd" user "Package Geometry/Place Bound Top")
		(29 "B.CrtYd" user "Package Geometry/Place Bound Bottom")
		(35 "F.Fab" user "Ref Des/Assembly Top")
		(33 "B.Fab" user "Ref Des/Assembly Bottom")
	)
	(footprint ""
		(layer "F.Cu")
		(at 41.913302 -63.756794 90)
		(property "Reference" "R201"
			(at 0 0 90)
			(layer "F.SilkS")
			(hide yes)
			(effects
				(font
					(size 1.27 1.27)
				)
			)
		)
		(property "Value" ""
			(at 0 0 90)
			(layer "F.Fab")
			(effects
				(font
					(size 1.27 1.27)
				)
			)
		)
		(duplicate_pad_numbers_are_jumpers no)
		(fp_line
			(start 0.7874 -0.4064)
			(end 0.7874 0.4064)
			(stroke
				(width 0.1524)
				(type default)
			)
			(layer "F.SilkS")
		)
		(fp_line
			(start -0.7874 -0.4064)
			(end 0.7874 -0.4064)
			(stroke
				(width 0.1524)
				(type default)
			)
			(layer "F.SilkS")
		)
		(fp_line
			(start 0.7874 0.4064)
			(end -0.7874 0.4064)
			(stroke
				(width 0.1524)
				(type default)
			)
			(layer "F.SilkS")
		)
		(fp_line
			(start -0.7874 0.4064)
			(end -0.7874 -0.4064)
			(stroke
				(width 0.1524)
				(type default)
			)
			(layer "F.SilkS")
		)
		(fp_line
			(start -0.12065 -0.305054)
			(end -0.12065 -0.2794)
			(stroke
				(width 0.1)
				(type default)
			)
			(layer "F.Fab")
		)
		(fp_line
			(start -0.67945 -0.305054)
			(end -0.12065 -0.305054)
			(stroke
				(width 0.1)
				(type default)
			)
			(layer "F.Fab")
		)
		(fp_line
			(start 0.67945 -0.3048)
			(end 0.67945 0.3048)
			(stroke
				(width 0.1)
				(type default)
			)
			(layer "F.Fab")
		)
		(fp_line
			(start 0.12065 -0.3048)
			(end 0.67945 -0.3048)
			(stroke
				(width 0.1)
				(type default)
			)
			(layer "F.Fab")
		)
		(fp_line
			(start 0.12065 -0.2794)
			(end 0.12065 -0.3048)
			(stroke
				(width 0.1)
				(type default)
			)
			(layer "F.Fab")
		)
		(fp_line
			(start -0.12065 -0.2794)
			(end 0.12065 -0.2794)
			(stroke
				(width 0.1)
				(type default)
			)
			(layer "F.Fab")
		)
		(fp_line
			(start 0.120396 0.2794)
			(end -0.12065 0.2794)
			(stroke
				(width 0.1)
				(type default)
			)
			(layer "F.Fab")
		)
		(fp_line
			(start -0.12065 0.2794)
			(end -0.12065 0.3048)
			(stroke
				(width 0.1)
				(type default)
			)
			(layer "F.Fab")
		)
		(fp_line
			(start 0.67945 0.3048)
			(end 0.120396 0.3048)
			(stroke
				(width 0.1)
				(type default)
			)
			(layer "F.Fab")
		)
		(fp_line
			(start 0.120396 0.3048)
			(end 0.120396 0.2794)
			(stroke
				(width 0.1)
				(type default)
			)
			(layer "F.Fab")
		)
		(fp_line
			(start -0.12065 0.3048)
			(end -0.67945 0.3048)
			(stroke
				(width 0.1)
				(type default)
			)
			(layer "F.Fab")
		)
		(fp_line
			(start -0.67945 0.3048)
			(end -0.67945 -0.305054)
			(stroke
				(width 0.1)
				(type default)
			)
			(layer "F.Fab")
		)
		(pad "1" smd circle
			(at -0.40005 0 90)
			(size 0 0)
			(layers "F.Cu" "F.Mask" "F.Paste")
			(net "I3C4_SDA_R")
		)
		(pad "2" smd circle
			(at 0.40005 0 90)
			(size 0 0)
			(layers "F.Cu" "F.Mask" "F.Paste")
			(net "I3C4_SPD_SDA")
		)
	)
	(footprint ""
		(layer "F.Cu")
		(at 11.551666 -12.546838 90)
		(property "Reference" "U31"
			(at -0.608838 -1.618996 90)
			(unlocked yes)
			(layer "F.SilkS")
			(effects
				(font
					(size 0.7874 0.5842)
					(thickness 0.1524)
				)
				(justify left)
			)
		)
		(property "Value" ""
			(at 0 0 90)
			(layer "F.Fab")
			(effects
				(font
					(size 1.27 1.27)
				)
			)
		)
		(duplicate_pad_numbers_are_jumpers no)
		(fp_line
			(start 1.4986 -1.100074)
			(end 1.4986 1.100074)
			(stroke
				(width 0.1524)
				(type default)
			)
			(layer "F.SilkS")
		)
		(fp_line
			(start -1.4986 -1.100074)
			(end 1.4986 -1.100074)
			(stroke
				(width 0.1524)
				(type default)
			)
			(layer "F.SilkS")
		)
		(fp_line
			(start 1.4986 1.100074)
			(end -1.4986 1.100074)
			(stroke
				(width 0.1524)
				(type default)
			)
			(layer "F.SilkS")
		)
		(fp_line
			(start -1.4986 1.100074)
			(end -1.4986 -1.100074)
			(stroke
				(width 0.1524)
				(type default)
			)
			(layer "F.SilkS")
		)
		(fp_poly
			(pts
				(xy -2.321052 -1.41732) (xy -1.879346 -1.859026) (xy -1.719834 -1.235456)
			)
			(stroke
				(width 0)
				(type default)
			)
			(fill yes)
			(layer "F.SilkS")
		)
		(fp_line
			(start 0.67437 -1.100074)
			(end 0.67437 1.100074)
			(stroke
				(width 0.1)
				(type default)
			)
			(layer "F.Fab")
		)
		(fp_line
			(start -0.67437 -1.100074)
			(end 0.67437 -1.100074)
			(stroke
				(width 0.1)
				(type default)
			)
			(layer "F.Fab")
		)
		(fp_line
			(start 0.67437 1.100074)
			(end -0.67437 1.100074)
			(stroke
				(width 0.1)
				(type default)
			)
			(layer "F.Fab")
		)
		(fp_line
			(start -0.67437 1.100074)
			(end -0.67437 -1.100074)
			(stroke
				(width 0.1)
				(type default)
			)
			(layer "F.Fab")
		)
		(fp_poly
			(pts
				(xy -2.20472 -0.338328) (xy -2.20472 -0.963168) (xy -1.651 -0.635)
			)
			(stroke
				(width 0)
				(type default)
			)
			(fill yes)
			(layer "F.Fab")
		)
		(pad "1" smd rect
			(at -0.889 -0.649986 90)
			(size 1.016 0.381)
			(layers "F.Cu" "F.Mask" "F.Paste")
			(net "TP_PWR_BUF")
		)
		(pad "2" smd rect
			(at -0.889 0 90)
			(size 1.016 0.381)
			(layers "F.Cu" "F.Mask" "F.Paste")
			(net "REAR_PWR_BTN_N")
		)
		(pad "3" smd rect
			(at -0.889 0.649986 90)
			(size 1.016 0.381)
			(layers "F.Cu" "F.Mask" "F.Paste")
			(net "GND")
		)
		(pad "4" smd rect
			(at 0.889 0.649986 90)
			(size 1.016 0.381)
			(layers "F.Cu" "F.Mask" "F.Paste")
			(net "PWR_BTN_BMC_N")
		)
		(pad "5" smd rect
			(at 0.889 -0.649986 90)
			(size 1.016 0.381)
			(layers "F.Cu" "F.Mask" "F.Paste")
			(net "P3V3_AUX")
		)
	)
)
